(kicad_pcb
	(version 20260206)
	(generator "pcbnew")
	(generator_version "10.0")
	(general
		(thickness 1.6)
		(legacy_teardrops no)
	)
	(paper "A4")
	(title_block
		(title "fcb — Lightning_FCB_BRD.brd")
		(comment 1 "Lightning (Wiwynn / Facebook NVMe JBOF) / footprints 431-437 of 495")
	)
	(layers
		(0 "F.Cu" signal "TOP")
		(4 "In1.Cu" signal "L2GND")
		(6 "In2.Cu" signal "L3VCC")
		(2 "B.Cu" signal "BOTTOM")
		(9 "F.Adhes" user "F.Adhesive")
		(11 "B.Adhes" user "B.Adhesive")
		(13 "F.Paste" user "Package Geometry/Pastemask Top")
		(15 "B.Paste" user "Package Geometry/Pastemask Bottom")
		(5 "F.SilkS" user "Ref Des/Silkscreen Top")
		(7 "B.SilkS" user "Ref Des/Silkscreen Bottom")
		(1 "F.Mask" user "Board Geometry/Soldermask Top")
		(3 "B.Mask" user "Board Geometry/Soldermask Bottom")
		(17 "Dwgs.User" user "User.Drawings")
		(19 "Cmts.User" user "User.Comments")
		(21 "Eco1.User" user "User.Eco1")
		(23 "Eco2.User" user "User.Eco2")
		(25 "Edge.Cuts" user "Board Geometry/Outline")
		(27 "Margin" user)
		(31 "F.CrtYd" user "Package Geometry/Place Bound Top")
		(29 "B.CrtYd" user "Package Geometry/Place Bound Bottom")
		(35 "F.Fab" user "Ref Des/Assembly Top")
		(33 "B.Fab" user "Ref Des/Assembly Bottom")
	)
	(footprint ""
		(layer "F.Cu")
		(at 4.897882 -78.481428)
		(property "Reference" "R113"
			(at 0 0 0)
			(layer "F.SilkS")
			(hide yes)
			(effects
				(font
					(size 1.27 1.27)
				)
			)
		)
		(property "Value" "2KR2F-3-GP"
			(at 0.064008 -3.993896 0)
			(unlocked yes)
			(layer "F.Fab")
			(hide yes)
			(effects
				(font
					(size 1.016 1.016)
					(thickness 0.1524)
				)
			)
		)
		(property "Device Type" "R402H16"
			(at 0.064008 -5.517896 0)
			(unlocked yes)
			(layer "F.Fab")
			(hide yes)
			(effects
				(font
					(size 1.016 1.016)
					(thickness 0.1524)
				)
			)
		)
		(duplicate_pad_numbers_are_jumpers no)
		(fp_line
			(start -0.508 -0.9398)
			(end -0.508 0.9398)
			(stroke
				(width 0.1524)
				(type default)
			)
			(layer "F.SilkS")
		)
		(fp_line
			(start 0.508 -0.9398)
			(end -0.508 -0.9398)
			(stroke
				(width 0.1524)
				(type default)
			)
			(layer "F.SilkS")
		)
		(fp_rect
			(start -0.508 0.9398)
			(end 0.508 -0.9398)
			(stroke
				(width 0)
				(type default)
			)
			(fill no)
			(layer "F.CrtYd")
		)
		(fp_rect
			(start -0.508 0.9398)
			(end 0.508 -0.9398)
			(stroke
				(width 0)
				(type default)
			)
			(fill no)
			(layer "F.Fab")
		)
		(pad "1" smd custom
			(at 0 -0.4445)
			(size 0.1397 0.1397)
			(layers "F.Cu" "F.Mask" "F.Paste")
			(net "LED_DR_LED4")
			(options
				(clearance outline)
				(anchor circle)
			)
			(primitives
				(gr_poly
					(pts
						(arc
							(start -0.1778 -0.2794)
							(mid -0.249642 -0.249642)
							(end -0.2794 -0.1778)
						)
						(arc
							(start -0.2794 0.1778)
							(mid -0.249642 0.249642)
							(end -0.1778 0.2794)
						)
						(arc
							(start 0.1778 0.2794)
							(mid 0.249642 0.249642)
							(end 0.2794 0.1778)
						)
						(arc
							(start 0.2794 -0.1778)
							(mid 0.249642 -0.249642)
							(end 0.1778 -0.2794)
						)
					)
					(width 0)
					(fill yes)
				)
			)
		)
		(pad "2" smd custom
			(at 0 0.4445)
			(size 0.1397 0.1397)
			(layers "F.Cu" "F.Mask" "F.Paste")
			(net "LED_DR_LED4_B")
			(options
				(clearance outline)
				(anchor circle)
			)
			(primitives
				(gr_poly
					(pts
						(arc
							(start -0.1778 -0.2794)
							(mid -0.249642 -0.249642)
							(end -0.2794 -0.1778)
						)
						(arc
							(start -0.2794 0.1778)
							(mid -0.249642 0.249642)
							(end -0.1778 0.2794)
						)
						(arc
							(start 0.1778 0.2794)
							(mid 0.249642 0.249642)
							(end 0.2794 0.1778)
						)
						(arc
							(start 0.2794 -0.1778)
							(mid 0.249642 -0.249642)
							(end 0.1778 -0.2794)
						)
					)
					(width 0)
					(fill yes)
				)
			)
		)
	)
	(footprint ""
		(layer "F.Cu")
		(at 42.0116 -362.839 180)
		(property "Reference" "PR49"
			(at 0 0 180)
			(layer "F.SilkS")
			(hide yes)
			(effects
				(font
					(size 1.27 1.27)
				)
			)
		)
		(property "Value" "4K7R2J-2-GP"
			(at 0.064008 -3.993896 180)
			(unlocked yes)
			(layer "F.Fab")
			(hide yes)
			(effects
				(font
					(size 1.016 1.016)
					(thickness 0.1524)
				)
			)
		)
		(property "Device Type" "R402H16"
			(at 0.064008 -5.517896 180)
			(unlocked yes)
			(layer "F.Fab")
			(hide yes)
			(effects
				(font
					(size 1.016 1.016)
					(thickness 0.1524)
				)
			)
		)
		(duplicate_pad_numbers_are_jumpers no)
		(fp_line
			(start 0.508 -0.9398)
			(end -0.508 -0.9398)
			(stroke
				(width 0.1524)
				(type default)
			)
			(layer "F.SilkS")
		)
		(fp_line
			(start -0.508 -0.9398)
			(end -0.508 0.9398)
			(stroke
				(width 0.1524)
				(type default)
			)
			(layer "F.SilkS")
		)
		(fp_rect
			(start -0.508 0.9398)
			(end 0.508 -0.9398)
			(stroke
				(width 0)
				(type default)
			)
			(fill no)
			(layer "F.CrtYd")
		)
		(fp_rect
			(start -0.508 0.9398)
			(end 0.508 -0.9398)
			(stroke
				(width 0)
				(type default)
			)
			(fill no)
			(layer "F.Fab")
		)
		(pad "1" smd custom
			(at 0 -0.4445 180)
			(size 0.1397 0.1397)
			(layers "F.Cu" "F.Mask" "F.Paste")
			(net "GND")
			(options
				(clearance outline)
				(anchor circle)
			)
			(primitives
				(gr_poly
					(pts
						(arc
							(start -0.1778 -0.2794)
							(mid -0.249642 -0.249642)
							(end -0.2794 -0.1778)
						)
						(arc
							(start -0.2794 0.1778)
							(mid -0.249642 0.249642)
							(end -0.1778 0.2794)
						)
						(arc
							(start 0.1778 0.2794)
							(mid 0.249642 0.249642)
							(end 0.2794 0.1778)
						)
						(arc
							(start 0.2794 -0.1778)
							(mid 0.249642 -0.249642)
							(end 0.1778 -0.2794)
						)
					)
					(width 0)
					(fill yes)
				)
			)
		)
		(pad "2" smd custom
			(at 0 0.4445 180)
			(size 0.1397 0.1397)
			(layers "F.Cu" "F.Mask" "F.Paste")
			(net "ADM1276_LATCH#")
			(options
				(clearance outline)
				(anchor circle)
			)
			(primitives
				(gr_poly
					(pts
						(arc
							(start -0.1778 -0.2794)
							(mid -0.249642 -0.249642)
							(end -0.2794 -0.1778)
						)
						(arc
							(start -0.2794 0.1778)
							(mid -0.249642 0.249642)
							(end -0.1778 0.2794)
						)
						(arc
							(start 0.1778 0.2794)
							(mid 0.249642 0.249642)
							(end 0.2794 0.1778)
						)
						(arc
							(start 0.2794 -0.1778)
							(mid 0.249642 -0.249642)
							(end 0.1778 -0.2794)
						)
					)
					(width 0)
					(fill yes)
				)
			)
		)
	)
	(footprint ""
		(layer "F.Cu")
		(at 24.2824 -361.188 180)
		(property "Reference" "PR11"
			(at 0 0 180)
			(layer "F.SilkS")
			(hide yes)
			(effects
				(font
					(size 1.27 1.27)
				)
			)
		)
		(property "Value" "150KR2F-L-GP"
			(at 0.064008 -3.993896 180)
			(unlocked yes)
			(layer "F.Fab")
			(hide yes)
			(effects
				(font
					(size 1.016 1.016)
					(thickness 0.1524)
				)
			)
		)
		(property "Device Type" "R402H16"
			(at 0.064008 -5.517896 180)
			(unlocked yes)
			(layer "F.Fab")
			(hide yes)
			(effects
				(font
					(size 1.016 1.016)
					(thickness 0.1524)
				)
			)
		)
		(duplicate_pad_numbers_are_jumpers no)
		(fp_line
			(start 0.508 -0.9398)
			(end -0.508 -0.9398)
			(stroke
				(width 0.1524)
				(type default)
			)
			(layer "F.SilkS")
		)
		(fp_line
			(start -0.508 -0.9398)
			(end -0.508 0.9398)
			(stroke
				(width 0.1524)
				(type default)
			)
			(layer "F.SilkS")
		)
		(fp_rect
			(start -0.508 0.9398)
			(end 0.508 -0.9398)
			(stroke
				(width 0)
				(type default)
			)
			(fill no)
			(layer "F.CrtYd")
		)
		(fp_rect
			(start -0.508 0.9398)
			(end 0.508 -0.9398)
			(stroke
				(width 0)
				(type default)
			)
			(fill no)
			(layer "F.Fab")
		)
		(pad "1" smd custom
			(at 0 -0.4445 180)
			(size 0.1397 0.1397)
			(layers "F.Cu" "F.Mask" "F.Paste")
			(net "ADM1276_ADR")
			(options
				(clearance outline)
				(anchor circle)
			)
			(primitives
				(gr_poly
					(pts
						(arc
							(start -0.1778 -0.2794)
							(mid -0.249642 -0.249642)
							(end -0.2794 -0.1778)
						)
						(arc
							(start -0.2794 0.1778)
							(mid -0.249642 0.249642)
							(end -0.1778 0.2794)
						)
						(arc
							(start 0.1778 0.2794)
							(mid 0.249642 0.249642)
							(end 0.2794 0.1778)
						)
						(arc
							(start 0.2794 -0.1778)
							(mid 0.249642 -0.249642)
							(end 0.1778 -0.2794)
						)
					)
					(width 0)
					(fill yes)
				)
			)
		)
		(pad "2" smd custom
			(at 0 0.4445 180)
			(size 0.1397 0.1397)
			(layers "F.Cu" "F.Mask" "F.Paste")
			(net "GND")
			(options
				(clearance outline)
				(anchor circle)
			)
			(primitives
				(gr_poly
					(pts
						(arc
							(start -0.1778 -0.2794)
							(mid -0.249642 -0.249642)
							(end -0.2794 -0.1778)
						)
						(arc
							(start -0.2794 0.1778)
							(mid -0.249642 0.249642)
							(end -0.1778 0.2794)
						)
						(arc
							(start 0.1778 0.2794)
							(mid 0.249642 0.249642)
							(end 0.2794 0.1778)
						)
						(arc
							(start 0.2794 -0.1778)
							(mid 0.249642 -0.249642)
							(end 0.1778 -0.2794)
						)
					)
					(width 0)
					(fill yes)
				)
			)
		)
	)
	(footprint ""
		(layer "F.Cu")
		(at 44.704 -122.428)
		(property "Reference" "PR62"
			(at 0 0 0)
			(layer "F.SilkS")
			(hide yes)
			(effects
				(font
					(size 1.27 1.27)
				)
			)
		)
		(property "Value" "D002R2512F-GP"
			(at -3.228594 -1.194054 0)
			(unlocked yes)
			(layer "F.Fab")
			(hide yes)
			(effects
				(font
					(size 1.016 1.016)
					(thickness 0.1524)
				)
			)
		)
		(property "Device Type" "R2512-2H32"
			(at -3.228594 -2.718054 0)
			(unlocked yes)
			(layer "F.Fab")
			(hide yes)
			(effects
				(font
					(size 1.016 1.016)
					(thickness 0.1524)
				)
			)
		)
		(duplicate_pad_numbers_are_jumpers no)
		(fp_line
			(start -1.9685 -3.81)
			(end 1.9685 -3.81)
			(stroke
				(width 0.1524)
				(type default)
			)
			(layer "F.SilkS")
		)
		(fp_line
			(start -1.9685 3.81)
			(end -1.9685 -3.81)
			(stroke
				(width 0.1524)
				(type default)
			)
			(layer "F.SilkS")
		)
		(fp_line
			(start 1.9685 -3.81)
			(end 1.9685 3.81)
			(stroke
				(width 0.1524)
				(type default)
			)
			(layer "F.SilkS")
		)
		(fp_line
			(start 1.9685 3.81)
			(end -1.9685 3.81)
			(stroke
				(width 0.1524)
				(type default)
			)
			(layer "F.SilkS")
		)
		(fp_rect
			(start -1.5875 3.175)
			(end 1.5875 -3.175)
			(stroke
				(width 0)
				(type default)
			)
			(fill no)
			(layer "F.CrtYd")
		)
		(fp_poly
			(pts
				(xy -2.2225 3.8862) (xy -2.2225 0.00254) (xy -1.5875 0.00254) (xy -1.5875 3.175) (xy 1.5875 3.175)
				(xy 1.5875 -3.175) (xy -1.5875 -3.175) (xy -1.5875 -0.00254) (xy -2.2225 -0.00254) (xy -2.2225 -3.8862)
				(xy 2.2225 -3.8862) (xy 2.2225 3.8862)
			)
			(stroke
				(width 0)
				(type default)
			)
			(fill no)
			(layer "F.CrtYd")
		)
		(fp_rect
			(start -2.2225 3.8862)
			(end 2.2225 -3.8862)
			(stroke
				(width 0)
				(type default)
			)
			(fill no)
			(layer "F.Fab")
		)
		(pad "1" smd rect
			(at 0 -2.273808)
			(size 3.429 2.5654)
			(layers "F.Cu" "F.Mask" "F.Paste")
			(net "P12V")
		)
		(pad "2" smd rect
			(at 0 2.273808)
			(size 3.429 2.5654)
			(layers "F.Cu" "F.Mask" "F.Paste")
			(net "P12VL_NET")
		)
	)
	(footprint ""
		(layer "F.Cu")
		(at 23.622 -366.4712 -90)
		(property "Reference" "C58"
			(at 0 0 270)
			(layer "F.SilkS")
			(hide yes)
			(effects
				(font
					(size 1.27 1.27)
				)
			)
		)
		(property "Value" "SCD1U25V2KX-GP"
			(at 1.1811 -2.7051 270)
			(unlocked yes)
			(layer "F.Fab")
			(hide yes)
			(effects
				(font
					(size 1.016 1.016)
					(thickness 0.1524)
				)
			)
		)
		(property "Device Type" "C402H22"
			(at 1.1811 -4.2291 270)
			(unlocked yes)
			(layer "F.Fab")
			(hide yes)
			(effects
				(font
					(size 1.016 1.016)
					(thickness 0.1524)
				)
			)
		)
		(duplicate_pad_numbers_are_jumpers no)
		(fp_rect
			(start -0.4318 0.9525)
			(end 0.4318 -0.9525)
			(stroke
				(width 0)
				(type default)
			)
			(fill no)
			(layer "F.CrtYd")
		)
		(fp_rect
			(start -0.4318 0.9525)
			(end 0.4318 -0.9525)
			(stroke
				(width 0)
				(type default)
			)
			(fill no)
			(layer "F.Fab")
		)
		(pad "1" smd custom
			(at 0 -0.4445 270)
			(size 0.1524 0.1524)
			(layers "F.Cu" "F.Mask" "F.Paste")
			(net "ADM1276_ISET")
			(options
				(clearance outline)
				(anchor circle)
			)
			(primitives
				(gr_poly
					(pts
						(arc
							(start 0.3048 -0.2032)
							(mid 0.275042 -0.275042)
							(end 0.2032 -0.3048)
						)
						(arc
							(start -0.2032 -0.3048)
							(mid -0.275042 -0.275042)
							(end -0.3048 -0.2032)
						)
						(arc
							(start -0.3048 0.2032)
							(mid -0.275042 0.275042)
							(end -0.2032 0.3048)
						)
						(arc
							(start 0.2032 0.3048)
							(mid 0.275042 0.275042)
							(end 0.3048 0.2032)
						)
					)
					(width 0)
					(fill yes)
				)
			)
		)
		(pad "2" smd custom
			(at 0 0.4445 270)
			(size 0.1524 0.1524)
			(layers "F.Cu" "F.Mask" "F.Paste")
			(net "GND")
			(options
				(clearance outline)
				(anchor circle)
			)
			(primitives
				(gr_poly
					(pts
						(arc
							(start 0.3048 -0.2032)
							(mid 0.275042 -0.275042)
							(end 0.2032 -0.3048)
						)
						(arc
							(start -0.2032 -0.3048)
							(mid -0.275042 -0.275042)
							(end -0.3048 -0.2032)
						)
						(arc
							(start -0.3048 0.2032)
							(mid -0.275042 0.275042)
							(end -0.2032 0.3048)
						)
						(arc
							(start 0.2032 0.3048)
							(mid 0.275042 0.275042)
							(end 0.3048 0.2032)
						)
					)
					(width 0)
					(fill yes)
				)
			)
		)
	)
	(footprint ""
		(layer "F.Cu")
		(at 23.241 -361.188)
		(property "Reference" "PR5"
			(at 0 0 0)
			(layer "F.SilkS")
			(hide yes)
			(effects
				(font
					(size 1.27 1.27)
				)
			)
		)
		(property "Value" "0R2J-2-GP"
			(at 0.064008 -3.993896 0)
			(unlocked yes)
			(layer "F.Fab")
			(hide yes)
			(effects
				(font
					(size 1.016 1.016)
					(thickness 0.1524)
				)
			)
		)
		(property "Device Type" "R402H16"
			(at 0.064008 -5.517896 0)
			(unlocked yes)
			(layer "F.Fab")
			(hide yes)
			(effects
				(font
					(size 1.016 1.016)
					(thickness 0.1524)
				)
			)
		)
		(duplicate_pad_numbers_are_jumpers no)
		(fp_line
			(start -0.508 -0.9398)
			(end -0.508 0.9398)
			(stroke
				(width 0.1524)
				(type default)
			)
			(layer "F.SilkS")
		)
		(fp_line
			(start 0.508 -0.9398)
			(end -0.508 -0.9398)
			(stroke
				(width 0.1524)
				(type default)
			)
			(layer "F.SilkS")
		)
		(fp_rect
			(start -0.508 0.9398)
			(end 0.508 -0.9398)
			(stroke
				(width 0)
				(type default)
			)
			(fill no)
			(layer "F.CrtYd")
		)
		(fp_rect
			(start -0.508 0.9398)
			(end 0.508 -0.9398)
			(stroke
				(width 0)
				(type default)
			)
			(fill no)
			(layer "F.Fab")
		)
		(pad "1" smd custom
			(at 0 -0.4445)
			(size 0.1397 0.1397)
			(layers "F.Cu" "F.Mask" "F.Paste")
			(net "ADM1276_VCAP")
			(options
				(clearance outline)
				(anchor circle)
			)
			(primitives
				(gr_poly
					(pts
						(arc
							(start -0.1778 -0.2794)
							(mid -0.249642 -0.249642)
							(end -0.2794 -0.1778)
						)
						(arc
							(start -0.2794 0.1778)
							(mid -0.249642 0.249642)
							(end -0.1778 0.2794)
						)
						(arc
							(start 0.1778 0.2794)
							(mid 0.249642 0.249642)
							(end 0.2794 0.1778)
						)
						(arc
							(start 0.2794 -0.1778)
							(mid 0.249642 -0.249642)
							(end 0.1778 -0.2794)
						)
					)
					(width 0)
					(fill yes)
				)
			)
		)
		(pad "2" smd custom
			(at 0 0.4445)
			(size 0.1397 0.1397)
			(layers "F.Cu" "F.Mask" "F.Paste")
			(net "ADM1276_ADR")
			(options
				(clearance outline)
				(anchor circle)
			)
			(primitives
				(gr_poly
					(pts
						(arc
							(start -0.1778 -0.2794)
							(mid -0.249642 -0.249642)
							(end -0.2794 -0.1778)
						)
						(arc
							(start -0.2794 0.1778)
							(mid -0.249642 0.249642)
							(end -0.1778 0.2794)
						)
						(arc
							(start 0.1778 0.2794)
							(mid 0.249642 0.249642)
							(end 0.2794 0.1778)
						)
						(arc
							(start 0.2794 -0.1778)
							(mid 0.249642 -0.249642)
							(end 0.1778 -0.2794)
						)
					)
					(width 0)
					(fill yes)
				)
			)
		)
	)
	(footprint ""
		(layer "F.Cu")
		(at 21.766784 -214.4014 90)
		(property "Reference" "R130"
			(at 0 0 90)
			(layer "F.SilkS")
			(hide yes)
			(effects
				(font
					(size 1.27 1.27)
				)
			)
		)
		(property "Value" "4K7R2F-GP"
			(at 0.064008 -3.993896 90)
			(unlocked yes)
			(layer "F.Fab")
			(hide yes)
			(effects
				(font
					(size 1.016 1.016)
					(thickness 0.1524)
				)
			)
		)
		(property "Device Type" "R402H16"
			(at 0.064008 -5.517896 90)
			(unlocked yes)
			(layer "F.Fab")
			(hide yes)
			(effects
				(font
					(size 1.016 1.016)
					(thickness 0.1524)
				)
			)
		)
		(duplicate_pad_numbers_are_jumpers no)
		(fp_line
			(start 0.508 -0.9398)
			(end -0.508 -0.9398)
			(stroke
				(width 0.1524)
				(type default)
			)
			(layer "F.SilkS")
		)
		(fp_line
			(start -0.508 -0.9398)
			(end -0.508 0.9398)
			(stroke
				(width 0.1524)
				(type default)
			)
			(layer "F.SilkS")
		)
		(fp_rect
			(start -0.508 0.9398)
			(end 0.508 -0.9398)
			(stroke
				(width 0)
				(type default)
			)
			(fill no)
			(layer "F.CrtYd")
		)
		(fp_rect
			(start -0.508 0.9398)
			(end 0.508 -0.9398)
			(stroke
				(width 0)
				(type default)
			)
			(fill no)
			(layer "F.Fab")
		)
		(pad "1" smd custom
			(at 0 -0.4445 90)
			(size 0.1397 0.1397)
			(layers "F.Cu" "F.Mask" "F.Paste")
			(net "P3V3")
			(options
				(clearance outline)
				(anchor circle)
			)
			(primitives
				(gr_poly
					(pts
						(arc
							(start -0.1778 -0.2794)
							(mid -0.249642 -0.249642)
							(end -0.2794 -0.1778)
						)
						(arc
							(start -0.2794 0.1778)
							(mid -0.249642 0.249642)
							(end -0.1778 0.2794)
						)
						(arc
							(start 0.1778 0.2794)
							(mid 0.249642 0.249642)
							(end 0.2794 0.1778)
						)
						(arc
							(start 0.2794 -0.1778)
							(mid 0.249642 -0.249642)
							(end 0.1778 -0.2794)
						)
					)
					(width 0)
					(fill yes)
				)
			)
		)
		(pad "2" smd custom
			(at 0 0.4445 90)
			(size 0.1397 0.1397)
			(layers "F.Cu" "F.Mask" "F.Paste")
			(net "PWM_OUT_FAN6")
			(options
				(clearance outline)
				(anchor circle)
			)
			(primitives
				(gr_poly
					(pts
						(arc
							(start -0.1778 -0.2794)
							(mid -0.249642 -0.249642)
							(end -0.2794 -0.1778)
						)
						(arc
							(start -0.2794 0.1778)
							(mid -0.249642 0.249642)
							(end -0.1778 0.2794)
						)
						(arc
							(start 0.1778 0.2794)
							(mid 0.249642 0.249642)
							(end 0.2794 0.1778)
						)
						(arc
							(start 0.2794 -0.1778)
							(mid 0.249642 -0.249642)
							(end 0.1778 -0.2794)
						)
					)
					(width 0)
					(fill yes)
				)
			)
		)
	)
)
